G04 ================== begin FILE IDENTIFICATION RECORD ==================*
G04 Layout Name:  12433-2a.brd*
G04 Film Name:    BSMD*
G04 File Format:  Gerber RS274X*
G04 File Origin:  Cadence Allegro 16.5-S056*
G04 Origin Date:  Fri Dec 11 16:47:33 2015*
G04 *
G04 Layer:  VIA CLASS/PASTEMASK_BOTTOM*
G04 Layer:  PIN/PASTEMASK_BOTTOM*
G04 Layer:  PACKAGE GEOMETRY/PASTEMASK_BOTTOM*
G04 Layer:  DRAWING FORMAT/LAYER_PCB_STORY*
G04 Layer:  DRAWING FORMAT/LAYER_PAST_B*
G04 Layer:  BOARD GEOMETRY/PANEL_OUTLINE*
G04 *
G04 Offset:    (0.00 0.00)*
G04 Mirror:    No*
G04 Mode:      Positive*
G04 Rotation:  0*
G04 FullContactRelief:  No*
G04 UndefLineWidth:     6.00*
G04 ================== end FILE IDENTIFICATION RECORD ====================*
%FSLAX35Y35*MOIN*%
%IR0*IPPOS*OFA0.00000B0.00000*MIA0B0*SFA1.00000B1.00000*%
%ADD11R,.05X.05*%
%ADD10C,.14*%
%ADD13C,.02*%
%ADD14C,.006*%
G75*
%LPD*%
G75*
G54D10*
X-222440Y19685D03*
Y1948818D03*
X643700Y19685D03*
Y1948818D03*
G54D11*
X-181139Y20007D03*
X-180444Y1947256D03*
X150000Y64500D03*
X152500Y1906000D03*
X601704Y21248D03*
X602399Y1948497D03*
G36*
G01X96467Y1729085D02*
G03X96447I-10J18750D01*
G01Y1737885D01*
G02X96467I10J9950D01*
G01Y1729085D01*
G37*
G36*
G01Y1804281D02*
G03X96447I-10J18750D01*
G01Y1813081D01*
G02X96467I10J9950D01*
G01Y1804281D01*
G37*
G36*
G01X178947Y1309990D02*
G03X178927I-10J18750D01*
G01Y1318790D01*
G02X178947I10J9950D01*
G01Y1309990D01*
G37*
G36*
G01X161427Y1729085D02*
G03X161407I-10J18750D01*
G01Y1737885D01*
G02X161427I10J9950D01*
G01Y1729085D01*
G37*
G36*
G01Y1804281D02*
G03X161407I-10J18750D01*
G01Y1813081D01*
G02X161427I10J9950D01*
G01Y1804281D01*
G37*
G54D13*
G01X-448201Y-66763D02*
X-480201D01*
G01X-448201Y-82763D02*
Y-162763D01*
G01Y-118263D02*
X752899D01*
G01X-448201Y-162763D02*
X752899D01*
G01X-452201Y-66763D02*
G02I-12000J0D01*
G01X-457351D02*
G02I-6850J0D01*
G01X-464201Y-82763D02*
Y-50763D01*
G01X-448201Y-82763D02*
X752899D01*
G01X-34601D02*
Y-162763D01*
G01X102899Y-82763D02*
Y-162763D01*
G01X217899Y-82763D02*
Y-162763D01*
G01X385399Y-82763D02*
Y-162763D01*
G01X555399Y-82763D02*
Y-162763D01*
G01X752899Y-82763D02*
Y-162763D01*
G01X780899Y-66763D02*
G02I-12000J0D01*
G01X775749D02*
G02I-6850J0D01*
G01X768899Y-82763D02*
Y-50763D01*
G01X784899Y-66763D02*
X752899D01*
G54D14*
G01X-430254Y-152763D02*
Y-135263D01*
G01X-421958D02*
X-430254Y-146055D01*
G01X-420648Y-152763D02*
X-426543Y-141097D01*
G01X-412973Y-152763D02*
Y-135263D01*
X-402929Y-152763D01*
Y-135263D01*
G01X-390451Y-152763D02*
X-392198Y-152471D01*
X-393726Y-151305D01*
X-395036Y-149555D01*
X-395910Y-147513D01*
X-396346Y-145180D01*
Y-142846D01*
X-395910Y-140513D01*
X-395036Y-138471D01*
X-393726Y-136722D01*
X-392198Y-135555D01*
X-390451Y-135263D01*
X-388705Y-135555D01*
X-387176Y-136722D01*
X-385866Y-138471D01*
X-384992Y-140513D01*
X-384556Y-142846D01*
Y-145180D01*
X-384992Y-147513D01*
X-385866Y-149555D01*
X-387176Y-151305D01*
X-388705Y-152471D01*
X-390451Y-152763D01*
G01X-377536D02*
X-368366Y-135263D01*
G01X-377536D02*
X-368366Y-152763D01*
G01X-362001Y-158596D02*
X-348901D01*
G01X-342099Y-152763D02*
Y-135263D01*
X-333803D01*
G01X-336859Y-143721D02*
X-342099D01*
G01X-325910Y-152763D02*
X-320451Y-135263D01*
X-314992Y-152763D01*
G01X-316958Y-146638D02*
X-323945D01*
G01X-307973Y-152763D02*
Y-135263D01*
X-297929Y-152763D01*
Y-135263D01*
G01X-263148Y-136722D02*
X-264458Y-135846D01*
X-265986Y-135263D01*
X-267733D01*
X-269698Y-136138D01*
X-271226Y-137596D01*
X-272318Y-139347D01*
X-273191Y-142263D01*
X-273410Y-144888D01*
X-272973Y-147513D01*
X-272318Y-149263D01*
X-271008Y-151013D01*
X-269479Y-152180D01*
X-267951Y-152763D01*
X-266423D01*
X-264894Y-152180D01*
X-263584Y-151305D01*
X-262492Y-150139D01*
G01X-250451Y-152763D02*
X-252198Y-152471D01*
X-253726Y-151305D01*
X-255036Y-149555D01*
X-255910Y-147513D01*
X-256346Y-145180D01*
Y-142846D01*
X-255910Y-140513D01*
X-255036Y-138471D01*
X-253726Y-136722D01*
X-252198Y-135555D01*
X-250451Y-135263D01*
X-248705Y-135555D01*
X-247176Y-136722D01*
X-245866Y-138471D01*
X-244992Y-140513D01*
X-244556Y-142846D01*
Y-145180D01*
X-244992Y-147513D01*
X-245866Y-149555D01*
X-247176Y-151305D01*
X-248705Y-152471D01*
X-250451Y-152763D01*
G01X-237973D02*
Y-135263D01*
X-227929Y-152763D01*
Y-135263D01*
G01X-215451D02*
Y-152763D01*
G01X-220473Y-135263D02*
X-210429D01*
G01X-202318Y-152763D02*
Y-135263D01*
X-196859D01*
X-195113Y-136138D01*
X-194021Y-137305D01*
X-193584Y-139638D01*
X-194021Y-141972D01*
X-195331Y-143430D01*
X-196859Y-144305D01*
X-202318D01*
G01X-196859D02*
X-193584Y-152763D01*
G01X-180451D02*
X-182198Y-152471D01*
X-183726Y-151305D01*
X-185036Y-149555D01*
X-185910Y-147513D01*
X-186346Y-145180D01*
Y-142846D01*
X-185910Y-140513D01*
X-185036Y-138471D01*
X-183726Y-136722D01*
X-182198Y-135555D01*
X-180451Y-135263D01*
X-178705Y-135555D01*
X-177176Y-136722D01*
X-175866Y-138471D01*
X-174992Y-140513D01*
X-174556Y-142846D01*
Y-145180D01*
X-174992Y-147513D01*
X-175866Y-149555D01*
X-177176Y-151305D01*
X-178705Y-152471D01*
X-180451Y-152763D01*
G01X-167318Y-135263D02*
Y-152763D01*
X-158584D01*
G01X-126205Y-143430D02*
X-125331Y-142555D01*
X-124676Y-141097D01*
X-124239Y-139054D01*
X-124676Y-137305D01*
X-125549Y-136138D01*
X-127078Y-135263D01*
X-132973D01*
Y-152763D01*
X-125768D01*
X-124239Y-151597D01*
X-123366Y-149846D01*
X-122929Y-147805D01*
X-123366Y-145763D01*
X-124676Y-144013D01*
X-126205Y-143430D01*
X-132973D01*
G01X-110451Y-152763D02*
X-112198Y-152471D01*
X-113726Y-151305D01*
X-115036Y-149555D01*
X-115910Y-147513D01*
X-116346Y-145180D01*
Y-142846D01*
X-115910Y-140513D01*
X-115036Y-138471D01*
X-113726Y-136722D01*
X-112198Y-135555D01*
X-110451Y-135263D01*
X-108705Y-135555D01*
X-107176Y-136722D01*
X-105866Y-138471D01*
X-104992Y-140513D01*
X-104556Y-142846D01*
Y-145180D01*
X-104992Y-147513D01*
X-105866Y-149555D01*
X-107176Y-151305D01*
X-108705Y-152471D01*
X-110451Y-152763D01*
G01X-98410D02*
X-92951Y-135263D01*
X-87492Y-152763D01*
G01X-89458Y-146638D02*
X-96445D01*
G01X-79818Y-152763D02*
Y-135263D01*
X-74359D01*
X-72613Y-136138D01*
X-71521Y-137305D01*
X-71084Y-139638D01*
X-71521Y-141972D01*
X-72831Y-143430D01*
X-74359Y-144305D01*
X-79818D01*
G01X-74359D02*
X-71084Y-152763D01*
G01X-62754D02*
Y-135263D01*
X-58388D01*
X-56641Y-136138D01*
X-55331Y-137305D01*
X-54239Y-139054D01*
X-53366Y-141097D01*
X-53148Y-144013D01*
X-53366Y-146930D01*
X-54239Y-148972D01*
X-55331Y-150722D01*
X-56641Y-151888D01*
X-58388Y-152763D01*
X-62754D01*
G01X-282378Y-107763D02*
Y-90263D01*
X-276701Y-104846D01*
X-271024Y-90263D01*
Y-107763D01*
G01X-259201D02*
X-260511Y-107471D01*
X-261821Y-106305D01*
X-262695Y-104263D01*
X-263131Y-101930D01*
X-262695Y-99596D01*
X-261821Y-97555D01*
X-260511Y-96388D01*
X-259201Y-96097D01*
X-257891Y-96388D01*
X-256581Y-97555D01*
X-255708Y-99596D01*
X-255489Y-101930D01*
X-255708Y-104263D01*
X-256581Y-106305D01*
X-257891Y-107471D01*
X-259201Y-107763D01*
G01X-237771Y-90263D02*
Y-107763D01*
G01Y-105139D02*
X-238644Y-106597D01*
X-239955Y-107471D01*
X-241483Y-107763D01*
X-243229Y-107180D01*
X-244539Y-105722D01*
X-245413Y-103972D01*
X-245631Y-101930D01*
X-245413Y-99888D01*
X-244539Y-98138D01*
X-243229Y-96680D01*
X-241483Y-96097D01*
X-239955Y-96388D01*
X-238863Y-96972D01*
X-237771Y-98138D01*
G01X-227476Y-99888D02*
X-220489D01*
X-221144Y-97846D01*
X-222236Y-96680D01*
X-223764Y-96097D01*
X-225293Y-96388D01*
X-226603Y-97263D01*
X-227476Y-99305D01*
X-227913Y-101055D01*
Y-102805D01*
X-227476Y-104555D01*
X-226384Y-106305D01*
X-225074Y-107471D01*
X-223546Y-107763D01*
X-222018Y-107180D01*
X-220489Y-105430D01*
G01X-206701Y-107763D02*
Y-90263D01*
G01X-222441Y169326D02*
Y39370D01*
G01D02*
G03X-214567Y31496I7874J0D01*
G01X-242126Y15000D02*
G03X-227126Y0I15000J0D01*
G01X-242126Y1953504D02*
Y15000D01*
G01X-215453Y19685D02*
G03I-6988J0D01*
G01X-84646Y0D02*
X-227126D01*
G01X-215453Y19685D02*
G03I-6988J0D01*
G01D02*
G03I-6988J0D01*
G01X-214567Y169326D02*
G03X-222441I-3937J0D01*
G01X-214567D02*
G03X-222441I-3937J0D01*
G01Y436255D02*
Y200034D01*
G01D02*
G03X-214567I3937J0D01*
G01X-222441D02*
G03X-214567I3937J0D01*
G01Y436255D02*
G03X-222441I-3937J0D01*
G01X-214567D02*
G03X-222441I-3937J0D01*
G01Y703184D02*
Y466963D01*
G01D02*
G03X-214567I3937J0D01*
G01X-222441D02*
G03X-214567I3937J0D01*
G01Y703184D02*
G03X-222441I-3937J0D01*
G01X-214567D02*
G03X-222441I-3937J0D01*
G01Y970901D02*
Y733892D01*
G01D02*
G03X-214567I3937J0D01*
G01X-222441D02*
G03X-214567I3937J0D01*
G01X-222441Y1234681D02*
Y997672D01*
G01X-214567Y970901D02*
G03X-222441I-3937J0D01*
G01Y997672D02*
G03X-214567I3937J0D01*
G01Y970901D02*
G03X-222441I-3937J0D01*
G01Y997672D02*
G03X-214567I3937J0D01*
G01X-222441Y1501610D02*
Y1265389D01*
G01D02*
G03X-214567I3937J0D01*
G01Y1234681D02*
G03X-222441I-3937J0D01*
G01Y1265389D02*
G03X-214567I3937J0D01*
G01Y1234681D02*
G03X-222441I-3937J0D01*
G01X-214567Y1501610D02*
G03X-222441I-3937J0D01*
G01X-214567D02*
G03X-222441I-3937J0D01*
G01Y1768539D02*
Y1532318D01*
G01D02*
G03X-214567I3937J0D01*
G01X-222441D02*
G03X-214567I3937J0D01*
G01Y1768539D02*
G03X-222441I-3937J0D01*
G01X-214567D02*
G03X-222441I-3937J0D01*
G01Y1799247D02*
G03X-214567I3937J0D01*
G01X-222441D02*
G03X-214567I3937J0D01*
G01X-222441Y1929134D02*
Y1799247D01*
G01X-214567Y1937008D02*
G03X-222441Y1929134I0J-7874D01*
G01X-227126Y1968504D02*
G03X-242126Y1953504I0J-15000D01*
G01X-215453Y1948819D02*
G03I-6988J0D01*
G01X-84638Y1968504D02*
X-227126D01*
G01X-215453Y1948819D02*
G03I-6988J0D01*
G01D02*
G03I-6988J0D01*
G01X-214567Y43307D02*
G03X-210630Y39370I3937J0D01*
G01X-214567Y43307D02*
G03X-210630Y39370I3937J0D01*
G01X-80709D02*
X-210630D01*
G01X-80709D02*
X-210630D01*
G01X-206693Y31496D02*
X-214567D01*
G01X-175984D02*
X-84646D01*
G01X-206693D02*
G03Y39370I0J3937D01*
G01X-175984D02*
G03Y31496I0J-3937D01*
G01X-206693D02*
X-214567D01*
G01X-84646Y0D02*
X-199567D01*
G01X-175984Y31496D02*
X-84646D01*
G01X-206693D02*
G03Y39370I0J3937D01*
G01X-175984D02*
G03Y31496I0J-3937D01*
G01X-214567Y43307D02*
Y1925197D01*
G01Y43307D02*
Y1925197D01*
G01Y149606D02*
Y43307D01*
G01Y149606D02*
Y43272D01*
G01Y1807087D02*
Y161417D01*
G01Y1807087D02*
Y161417D01*
G01Y1818898D02*
Y1925231D01*
G01Y1818898D02*
Y1925231D01*
G01X-210630Y1929134D02*
G03X-214567Y1925197I0J-3937D01*
G01X-210630Y1929134D02*
G03X-214567Y1925197I0J-3937D01*
G01X-210630Y1929134D02*
X-80709D01*
G01X-210630D02*
X-80709D01*
G01X-175984Y1937008D02*
G03Y1929134I0J-3937D01*
G01X-206693D02*
G03Y1937008I0J3937D01*
G01X-175984D02*
G03Y1929134I0J-3937D01*
G01X-206693D02*
G03Y1937008I0J3937D01*
G01X-175984D02*
X-84638D01*
G01X-214567D02*
X-206693D01*
G01X-84638Y1968504D02*
X-199567D01*
G01X-175984Y1937008D02*
X-84638D01*
G01X-214567D02*
X-206693D01*
G01X-76772Y3937D02*
G03X-72835Y0I3937J0D01*
G01X-76772Y35433D02*
G03X-80709Y39370I-3937J0D01*
G01X-76772Y35433D02*
G03X-80709Y39370I-3937J0D01*
G01X-76772Y3937D02*
G03X-72835Y0I3937J0D01*
G01X-11811D02*
X-72835D01*
G01X-11811D02*
X-72835D01*
G01X-76772Y3937D02*
Y35433D01*
G01Y3937D02*
Y35433D01*
G01X-72835Y0D02*
X-11811D01*
G01X-76772Y3937D02*
G03X-72835Y0I3937J0D01*
G01X-84646Y7874D02*
Y0D01*
G01X-76772Y7874D02*
G03X-84646I-3937J0D01*
G01Y31496D02*
G03X-76772I3937J0D01*
G01X-72835Y0D02*
X-11811D01*
G01X-76772Y3937D02*
G03X-72835Y0I3937J0D01*
G01X-84646Y7874D02*
Y0D01*
G01X-76772Y7874D02*
G03X-84646I-3937J0D01*
G01Y31496D02*
G03X-76772I3937J0D01*
G01X-80709Y1929134D02*
G03X-76772Y1933071I0J3937D01*
G01X-80709Y1929134D02*
G03X-76772Y1933071I0J3937D01*
G01D02*
Y1964567D01*
G01Y1933071D02*
Y1964567D01*
G01X-76763Y1937008D02*
G03X-84638I-3937J0D01*
G01X-72835Y1968504D02*
G03X-76772Y1964567I0J-3937D01*
G01X-72835Y1968504D02*
G03X-76772Y1964567I0J-3937D01*
G01X-72835Y1968504D02*
X-11811D01*
G01X-72835D02*
X-11811D01*
G01X-72835D02*
G03X-76772Y1964567I0J-3937D01*
G01X-11811Y1968504D02*
X-72835D01*
G01X-84638Y1960889D02*
Y1968504D01*
G01Y1960889D02*
G03X-76763I3938J0D01*
G01X-72835Y1968504D02*
G03X-76772Y1964567I0J-3937D01*
G01X-11811Y1968504D02*
X-72835D01*
G01X-84638Y1960889D02*
Y1968504D01*
G01Y1960889D02*
G03X-76763I3938J0D01*
G01X-14018Y-107763D02*
Y-90263D01*
X-8778D01*
X-7031Y-91138D01*
X-5721Y-93180D01*
X-5284Y-95513D01*
X-5721Y-97846D01*
X-6813Y-99596D01*
X-8778Y-100472D01*
X-14018D01*
G01X12652Y-91722D02*
X11342Y-90846D01*
X9814Y-90263D01*
X8067D01*
X6102Y-91138D01*
X4574Y-92596D01*
X3482Y-94347D01*
X2609Y-97263D01*
X2390Y-99888D01*
X2827Y-102513D01*
X3482Y-104263D01*
X4792Y-106013D01*
X6321Y-107180D01*
X7849Y-107763D01*
X9377D01*
X10906Y-107180D01*
X12216Y-106305D01*
X13308Y-105139D01*
G01X27095Y-98430D02*
X27969Y-97555D01*
X28624Y-96097D01*
X29061Y-94054D01*
X28624Y-92305D01*
X27751Y-91138D01*
X26222Y-90263D01*
X20327D01*
Y-107763D01*
X27532D01*
X29061Y-106597D01*
X29934Y-104846D01*
X30371Y-102805D01*
X29934Y-100763D01*
X28624Y-99013D01*
X27095Y-98430D01*
X20327D01*
G01X36299Y-113596D02*
X49399D01*
G01X55327Y-107763D02*
Y-90263D01*
X65371Y-107763D01*
Y-90263D01*
G01X77849Y-107763D02*
X76102Y-107471D01*
X74574Y-106305D01*
X73264Y-104555D01*
X72390Y-102513D01*
X71954Y-100180D01*
Y-97846D01*
X72390Y-95513D01*
X73264Y-93471D01*
X74574Y-91722D01*
X76102Y-90555D01*
X77849Y-90263D01*
X79595Y-90555D01*
X81124Y-91722D01*
X82434Y-93471D01*
X83308Y-95513D01*
X83744Y-97846D01*
Y-100180D01*
X83308Y-102513D01*
X82434Y-104555D01*
X81124Y-106305D01*
X79595Y-107471D01*
X77849Y-107763D01*
G01X-901Y-152763D02*
Y-135263D01*
X-3521Y-138763D01*
G01Y-152763D02*
X1719D01*
G01X12451Y-138180D02*
X13761Y-136430D01*
X15289Y-135555D01*
X17036Y-135263D01*
X19219Y-135846D01*
X20747Y-137305D01*
X21184Y-139054D01*
X20966Y-140805D01*
X20092Y-142263D01*
X15726Y-145180D01*
X13761Y-147221D01*
X12451Y-150139D01*
X12014Y-152763D01*
X21184D01*
G01X36719D02*
Y-135263D01*
X28640Y-147805D01*
X39558D01*
G01X46796Y-149263D02*
X48105Y-151305D01*
X49852Y-152471D01*
X51817Y-152763D01*
X53564Y-152471D01*
X55311Y-151013D01*
X56402Y-149263D01*
X56621Y-147513D01*
X56184Y-145472D01*
X54656Y-144013D01*
X53127Y-143430D01*
X51162D01*
G01X53127D02*
X54437Y-142555D01*
X55529Y-141097D01*
X55966Y-139347D01*
X55529Y-137596D01*
X54437Y-136138D01*
X52472Y-135263D01*
X50507Y-135555D01*
X48542Y-136722D01*
G01X64296Y-149263D02*
X65605Y-151305D01*
X67352Y-152471D01*
X69317Y-152763D01*
X71064Y-152471D01*
X72811Y-151013D01*
X73902Y-149263D01*
X74121Y-147513D01*
X73684Y-145472D01*
X72156Y-144013D01*
X70627Y-143430D01*
X68662D01*
G01X70627D02*
X71937Y-142555D01*
X73029Y-141097D01*
X73466Y-139347D01*
X73029Y-137596D01*
X71937Y-136138D01*
X69972Y-135263D01*
X68007Y-135555D01*
X66042Y-136722D01*
G01X-11811Y0D02*
G03X-7874Y3937I0J3937D01*
G01X-11811Y0D02*
G03X-7874Y3937I0J3937D01*
G01Y43110D02*
Y3937D01*
G01Y43110D02*
Y3937D01*
G01X0D02*
G03X3937Y0I3937J0D01*
G01X0Y3937D02*
G03X3937Y0I3937J0D01*
G01X0Y3937D02*
Y43110D01*
G01Y3937D02*
Y43110D01*
G01X64961Y0D02*
X3937D01*
G01X64961D02*
X3937D01*
G01X0Y3937D02*
G03X3937Y0I3937J0D01*
G01X0Y1964567D02*
Y3937D01*
G01X3937Y0D02*
X64961D01*
G01X-7874Y3937D02*
Y1964567D01*
G01X-11811Y0D02*
G03X-7874Y3937I0J3937D01*
G01X0Y11811D02*
G03X-7874I-3937J0D01*
G01Y42520D02*
G03X0I3937J0D01*
G01Y3937D02*
G03X3937Y0I3937J0D01*
G01X0Y1964567D02*
Y3937D01*
G01X3937Y0D02*
X64961D01*
G01X-7874Y3937D02*
Y1964567D01*
G01X-11811Y0D02*
G03X-7874Y3937I0J3937D01*
G01X0Y11811D02*
G03X-7874I-3937J0D01*
G01Y42520D02*
G03X0I3937J0D01*
G01X-7874Y93110D02*
Y43110D01*
G01Y93110D02*
Y43110D01*
G01X0D02*
Y93110D01*
G01Y43110D02*
Y93110D01*
G01X-7874Y214764D02*
Y93110D01*
G01Y214764D02*
Y93110D01*
G01X0D02*
Y214764D01*
G01Y93110D02*
Y214764D01*
G01X-7874Y226968D02*
Y214764D01*
G01Y226968D02*
Y214764D01*
G01Y342461D02*
Y226968D01*
G01Y342461D02*
Y226968D01*
G01X0Y226969D02*
Y342461D01*
G01Y226969D02*
Y342461D01*
G01Y214764D02*
Y226969D01*
G01Y214764D02*
Y226969D01*
G01Y278740D02*
G03X-7874I-3937J0D01*
G01X0D02*
G03X-7874I-3937J0D01*
G01Y354665D02*
Y342461D01*
G01Y354665D02*
Y342461D01*
G01X0D02*
Y354665D01*
G01Y342461D02*
Y354665D01*
G01X-7874Y309449D02*
G03X0I3937J0D01*
G01X-7874D02*
G03X0I3937J0D01*
G01X-7874Y476339D02*
Y354665D01*
G01Y476339D02*
Y354665D01*
G01X0D02*
Y476339D01*
G01Y354665D02*
Y476339D01*
G01X-7874Y526339D02*
Y476339D01*
G01Y526339D02*
Y476339D01*
G01X0D02*
Y526339D01*
G01Y476339D02*
Y526339D01*
G01X-7874Y736181D02*
Y526339D01*
G01Y736181D02*
Y526339D01*
G01X0D02*
Y736181D01*
G01Y526339D02*
Y736181D01*
G01Y545669D02*
G03X-7874I-3937J0D01*
G01X0D02*
G03X-7874I-3937J0D01*
G01Y576378D02*
G03X0I3937J0D01*
G01X-7874D02*
G03X0I3937J0D01*
G01X-7874Y786181D02*
Y736181D01*
G01Y786181D02*
Y736181D01*
G01X0D02*
Y786181D01*
G01Y736181D02*
Y786181D01*
G01X-7874Y907815D02*
Y786181D01*
G01Y907815D02*
Y786181D01*
G01X0D02*
Y907815D01*
G01Y786181D02*
Y907815D01*
G01X-7874Y862205D02*
G03X0I3937J0D01*
G01Y831496D02*
G03X-7874I-3937J0D01*
G01Y862205D02*
G03X0I3937J0D01*
G01Y831496D02*
G03X-7874I-3937J0D01*
G01Y920020D02*
Y907815D01*
G01Y920020D02*
Y907815D01*
G01X0D02*
Y920020D01*
G01Y907815D02*
Y920020D01*
G01X-7874Y1048484D02*
Y920020D01*
G01Y1048484D02*
Y920020D01*
G01X0D02*
Y1048484D01*
G01Y920020D02*
Y1048484D01*
G01X-7874Y1060689D02*
Y1048484D01*
G01Y1060689D02*
Y1048484D01*
G01Y1182323D02*
Y1060689D01*
G01Y1182323D02*
Y1060689D01*
G01X0D02*
Y1182323D01*
G01Y1060689D02*
Y1182323D01*
G01Y1048484D02*
Y1060689D01*
G01Y1048484D02*
Y1060689D01*
G01Y1106299D02*
G03X-7874I-3937J0D01*
G01X0D02*
G03X-7874I-3937J0D01*
G01Y1137008D02*
G03X0I3937J0D01*
G01X-7874D02*
G03X0I3937J0D01*
G01X-7874Y1232323D02*
Y1182323D01*
G01Y1232323D02*
Y1182323D01*
G01X0D02*
Y1232323D01*
G01Y1182323D02*
Y1232323D01*
G01X-7874Y1442165D02*
Y1232323D01*
G01Y1442165D02*
Y1232323D01*
G01X0D02*
Y1442165D01*
G01Y1232323D02*
Y1442165D01*
G01X-7874Y1422835D02*
G03X0I3937J0D01*
G01Y1392126D02*
G03X-7874I-3937J0D01*
G01Y1422835D02*
G03X0I3937J0D01*
G01Y1392126D02*
G03X-7874I-3937J0D01*
G01Y1492165D02*
Y1442165D01*
G01Y1492165D02*
Y1442165D01*
G01X0D02*
Y1492165D01*
G01Y1442165D02*
Y1492165D01*
G01X-7874Y1613839D02*
Y1492165D01*
G01Y1613839D02*
Y1492165D01*
G01X0D02*
Y1613839D01*
G01Y1492165D02*
Y1613839D01*
G01X-7874Y1626043D02*
Y1613839D01*
G01Y1626043D02*
Y1613839D01*
G01Y1741535D02*
Y1626043D01*
G01Y1741535D02*
Y1626043D01*
G01X0D02*
Y1741535D01*
G01Y1626043D02*
Y1741535D01*
G01Y1613839D02*
Y1626043D01*
G01Y1613839D02*
Y1626043D01*
G01Y1659055D02*
G03X-7874I-3937J0D01*
G01X0D02*
G03X-7874I-3937J0D01*
G01Y1689764D02*
G03X0I3937J0D01*
G01X-7874D02*
G03X0I3937J0D01*
G01X-7874Y1753740D02*
Y1741535D01*
G01Y1753740D02*
Y1741535D01*
G01Y1875394D02*
Y1753740D01*
G01Y1875394D02*
Y1753740D01*
G01X0D02*
Y1875394D01*
G01Y1753740D02*
Y1875394D01*
G01Y1741535D02*
Y1753740D01*
G01Y1741535D02*
Y1753740D01*
G01X-7874Y1925394D02*
Y1875394D01*
G01Y1925394D02*
Y1875394D01*
G01X0D02*
Y1925394D01*
G01Y1875394D02*
Y1925394D01*
G01X-7874Y1964567D02*
Y1925394D01*
G01Y1964567D02*
Y1925394D01*
G01X0D02*
Y1964567D01*
G01Y1925394D02*
Y1964567D01*
G01Y1925984D02*
G03X-7874I-3937J0D01*
G01X0D02*
G03X-7874I-3937J0D01*
G01Y1964567D02*
G03X-11811Y1968504I-3937J0D01*
G01X-7874Y1964567D02*
G03X-11811Y1968504I-3937J0D01*
G01X3937D02*
G03X0Y1964567I0J-3937D01*
G01X3937Y1968504D02*
G03X0Y1964567I0J-3937D01*
G01X3937Y1968504D02*
X64961D01*
G01X3937D02*
X64961D01*
G01X3937D02*
G03X0Y1964567I0J-3937D01*
G01X64961Y1968504D02*
X3937D01*
G01X-7874Y1964567D02*
G03X-11811Y1968504I-3937J0D01*
G01X-7874Y1956693D02*
G03X0I3937J0D01*
G01X3937Y1968504D02*
G03X0Y1964567I0J-3937D01*
G01X64961Y1968504D02*
X3937D01*
G01X-7874Y1964567D02*
G03X-11811Y1968504I-3937J0D01*
G01X-7874Y1956693D02*
G03X0I3937J0D01*
G01X168110Y31496D02*
X76763D01*
G01X72835Y39370D02*
G03X68898Y35433I0J-3937D01*
G01X72835Y39370D02*
G03X68898Y35433I0J-3937D01*
G01X64961Y0D02*
G03X68898Y3937I0J3937D01*
G01X64961Y0D02*
G03X68898Y3937I0J3937D01*
G01Y35433D02*
Y3937D01*
G01Y35433D02*
Y3937D01*
G01X202756Y39370D02*
X72835D01*
G01X202756D02*
X72835D01*
G01D02*
X202756D01*
G01X72835D02*
G03X68898Y35433I0J-3937D01*
G01Y3937D02*
Y35485D01*
G01X64961Y0D02*
G03X68898Y3937I0J3937D01*
G01X76763D02*
G03X80700Y0I3937J0D01*
G01X76763Y7615D02*
Y3937D01*
G01X80700Y0D02*
X340551D01*
G01X168110Y31496D02*
X76763D01*
G01Y7615D02*
G03X68889I-3937J0D01*
G01Y31496D02*
G03X76763I3937J0D01*
G01X72835Y39370D02*
X202756D01*
G01X72835D02*
G03X68898Y35433I0J-3937D01*
G01Y3937D02*
Y35485D01*
G01X64961Y0D02*
G03X68898Y3937I0J3937D01*
G01X76763D02*
G03X80700Y0I3937J0D01*
G01X76763Y7615D02*
Y3937D01*
G01X80700Y0D02*
X340551D01*
G01X168110Y31496D02*
X76763D01*
G01Y7615D02*
G03X68889I-3937J0D01*
G01Y31496D02*
G03X76763I3937J0D01*
G01X68898Y1933071D02*
G03X72835Y1929134I3937J0D01*
G01X68898Y1933071D02*
G03X72835Y1929134I3937J0D01*
G01D02*
X202756D01*
G01X72835D02*
X202756D01*
G01X68898Y1964567D02*
Y1933071D01*
G01Y1964567D02*
Y1933071D01*
G01D02*
Y1964567D01*
G01Y1933071D02*
G03X72835Y1929134I3937J0D01*
G01X202756D02*
X72835D01*
G01X68898Y1933071D02*
Y1964567D01*
G01Y1933071D02*
G03X72835Y1929134I3937J0D01*
G01X202756D02*
X72835D01*
G01X68898Y1964567D02*
G03X64961Y1968504I-3937J0D01*
G01X68898Y1964567D02*
G03X64961Y1968504I-3937J0D01*
G01X68898Y1964567D02*
G03X64961Y1968504I-3937J0D01*
G01X109377D02*
X80709D01*
G01D02*
G03X76772Y1964567I0J-3937D01*
G01Y1960630D02*
Y1964567D01*
G01X168110Y1937008D02*
X76772D01*
G01X68898Y1960630D02*
G03X76772I3937J0D01*
G01Y1937008D02*
G03X68898I-3937J0D01*
G01Y1964567D02*
G03X64961Y1968504I-3937J0D01*
G01X109377D02*
X80709D01*
G01D02*
G03X76772Y1964567I0J-3937D01*
G01Y1960630D02*
Y1964567D01*
G01X168110Y1937008D02*
X76772D01*
G01X68898Y1960630D02*
G03X76772I3937J0D01*
G01Y1937008D02*
G03X68898I-3937J0D01*
G01X128690Y-90263D02*
X134149Y-107763D01*
X139608Y-90263D01*
G01X156016Y-107763D02*
X147282D01*
Y-90263D01*
X156016D01*
G01X152522Y-98721D02*
X147282D01*
G01X164782Y-107763D02*
Y-90263D01*
X170241D01*
X171987Y-91138D01*
X173079Y-92305D01*
X173516Y-94638D01*
X173079Y-96972D01*
X171769Y-98430D01*
X170241Y-99305D01*
X164782D01*
G01X170241D02*
X173516Y-107763D01*
G01X186649Y-108346D02*
X186212Y-108055D01*
Y-107471D01*
X186649Y-107180D01*
X187086Y-107471D01*
Y-108055D01*
X186649Y-108346D01*
G01X118011Y1968504D02*
X142520D01*
G01X109377D02*
X110137D01*
G01D02*
G03X118011I3937J0D01*
G01X110137D02*
G03X118011I3937J0D01*
G01X147501Y-138180D02*
X148811Y-136430D01*
X150339Y-135555D01*
X152086Y-135263D01*
X154269Y-135846D01*
X155797Y-137305D01*
X156234Y-139054D01*
X156016Y-140805D01*
X155142Y-142263D01*
X150776Y-145180D01*
X148811Y-147221D01*
X147501Y-150139D01*
X147064Y-152763D01*
X156234D01*
G01X163690D02*
X169149Y-135263D01*
X174608Y-152763D01*
G01X172642Y-146638D02*
X165655D01*
G01X168110Y31496D02*
G03Y39370I0J3937D01*
G01Y31496D02*
G03Y39370I0J3937D01*
G01Y1929134D02*
G03Y1937008I0J3937D01*
G01Y1929134D02*
G03Y1937008I0J3937D01*
G01X340559Y1968504D02*
X142520D01*
G01X340559D02*
X142520D01*
G01X202756Y39370D02*
G03X206693Y43307I0J3937D01*
G01X202756Y39370D02*
G03X206693Y43307I0J3937D01*
G01X202756Y39370D02*
G03X206693Y43307I0J3937D01*
G01X218504Y39370D02*
X348425D01*
G01X214567Y43307D02*
G03X218504Y39370I3937J0D01*
G01X222441Y31496D02*
X198819D01*
G01X222441D02*
G03Y39370I0J3937D01*
G01X198819D02*
G03Y31496I0J-3937D01*
G01X202756Y39370D02*
G03X206693Y43307I0J3937D01*
G01X218504Y39370D02*
X348425D01*
G01X214567Y43307D02*
G03X218504Y39370I3937J0D01*
G01X222441Y31496D02*
X198819D01*
G01X222441D02*
G03Y39370I0J3937D01*
G01X198819D02*
G03Y31496I0J-3937D01*
G01X214567Y161417D02*
Y43307D01*
G01X206693Y1925197D02*
Y43307D01*
G01Y1925197D02*
Y43307D01*
G01Y161417D02*
Y1807087D01*
G01X214567D02*
Y161417D01*
G01Y169291D02*
G03X206693I-3937J0D01*
G01Y161417D02*
Y1807087D01*
G01X214567D02*
Y161417D01*
G01Y169291D02*
G03X206693I-3937J0D01*
G01Y200000D02*
G03X214567I3937J0D01*
G01X206693D02*
G03X214567I3937J0D01*
G01Y436220D02*
G03X206693I-3937J0D01*
G01X214567D02*
G03X206693I-3937J0D01*
G01Y466929D02*
G03X214567I3937J0D01*
G01X206693D02*
G03X214567I3937J0D01*
G01Y703149D02*
G03X206693I-3937J0D01*
G01X214567D02*
G03X206693I-3937J0D01*
G01Y733858D02*
G03X214567I3937J0D01*
G01X206693D02*
G03X214567I3937J0D01*
G01Y970867D02*
G03X206693I-3937J0D01*
G01Y997637D02*
G03X214567I3937J0D01*
G01Y970867D02*
G03X206693I-3937J0D01*
G01Y997637D02*
G03X214567I3937J0D01*
G01X206693Y1265355D02*
G03X214567I3937J0D01*
G01Y1234646D02*
G03X206693I-3937J0D01*
G01Y1265355D02*
G03X214567I3937J0D01*
G01Y1234646D02*
G03X206693I-3937J0D01*
G01X214567Y1501575D02*
G03X206693I-3937J0D01*
G01X214567D02*
G03X206693I-3937J0D01*
G01Y1532284D02*
G03X214567I3937J0D01*
G01X206693D02*
G03X214567I3937J0D01*
G01Y1768504D02*
G03X206693I-3937J0D01*
G01X214567D02*
G03X206693I-3937J0D01*
G01X214567Y1807087D02*
Y1925197D01*
G01X206693Y1799213D02*
G03X214567I3937J0D01*
G01X206693D02*
G03X214567I3937J0D01*
G01X206693Y1925197D02*
G03X202756Y1929134I-3937J0D01*
G01X206693Y1925197D02*
G03X202756Y1929134I-3937J0D01*
G01X206693Y1925197D02*
G03X202756Y1929134I-3937J0D01*
G01X218504D02*
G03X214567Y1925197I0J-3937D01*
G01X348425Y1929134D02*
X218504D01*
G01X198819Y1937008D02*
G03Y1929134I0J-3937D01*
G01X222441D02*
G03Y1937008I0J3937D01*
G01X206693Y1925197D02*
G03X202756Y1929134I-3937J0D01*
G01X218504D02*
G03X214567Y1925197I0J-3937D01*
G01X348425Y1929134D02*
X218504D01*
G01X198819Y1937008D02*
G03Y1929134I0J-3937D01*
G01X222441D02*
G03Y1937008I0J3937D01*
G01X198819D02*
X222441D01*
G01X198819D02*
X222441D01*
G01X253482Y-90263D02*
Y-107763D01*
X262216D01*
G01X279279D02*
Y-96097D01*
G01Y-98138D02*
X278406Y-96972D01*
X277095Y-96388D01*
X275567Y-96097D01*
X274039Y-96680D01*
X272729Y-97846D01*
X271855Y-99596D01*
X271419Y-101930D01*
X271855Y-104263D01*
X272729Y-106013D01*
X274039Y-107180D01*
X275567Y-107763D01*
X277095Y-107471D01*
X278406Y-106597D01*
X279279Y-105430D01*
G01X288264Y-113013D02*
X289574Y-113596D01*
X291321Y-113013D01*
X292412Y-111847D01*
X293286Y-110388D01*
X294595Y-105722D01*
X297434Y-96097D01*
G01X290447D02*
X294595Y-105722D01*
G01X307074Y-99888D02*
X314061D01*
X313406Y-97846D01*
X312314Y-96680D01*
X310786Y-96097D01*
X309257Y-96388D01*
X307947Y-97263D01*
X307074Y-99305D01*
X306637Y-101055D01*
Y-102805D01*
X307074Y-104555D01*
X308166Y-106305D01*
X309476Y-107471D01*
X311004Y-107763D01*
X312532Y-107180D01*
X314061Y-105430D01*
G01X324792Y-107763D02*
Y-96097D01*
G01Y-98430D02*
X325884Y-97263D01*
X326976Y-96388D01*
X328504Y-96097D01*
X329595Y-96388D01*
X330906Y-97263D01*
G01X342074Y-105722D02*
X343166Y-106888D01*
X344694Y-107763D01*
X346004D01*
X347314Y-107180D01*
X348187Y-106305D01*
X348624Y-105139D01*
X348406Y-103388D01*
X347532Y-102513D01*
X343602Y-100763D01*
X342729Y-98721D01*
X343166Y-97263D01*
X344039Y-96388D01*
X345349Y-96097D01*
X346659Y-96388D01*
X347969Y-97263D01*
G01X326103Y-143430D02*
X325229Y-142555D01*
X324574Y-141097D01*
X324137Y-139054D01*
X324574Y-137305D01*
X325447Y-136138D01*
X326976Y-135263D01*
X332871D01*
Y-152763D01*
X325666D01*
X324137Y-151597D01*
X323264Y-149846D01*
X322827Y-147805D01*
X323264Y-145763D01*
X324574Y-144013D01*
X326103Y-143430D01*
X332871D01*
G01X314934Y-150430D02*
X313187Y-151888D01*
X311222Y-152763D01*
X309476D01*
X307729Y-151888D01*
X306419Y-150430D01*
X305764Y-148388D01*
X306201Y-146347D01*
X307292Y-144596D01*
X309257Y-143430D01*
X311877Y-142846D01*
X313406Y-141680D01*
X314061Y-139638D01*
X313624Y-137596D01*
X312532Y-136138D01*
X311004Y-135263D01*
X309476D01*
X307947Y-135846D01*
X306637Y-137305D01*
G01X298526Y-152763D02*
Y-135263D01*
X292849Y-149846D01*
X287172Y-135263D01*
Y-152763D01*
G01X280152D02*
Y-135263D01*
X275786D01*
X274039Y-136138D01*
X272729Y-137305D01*
X271637Y-139054D01*
X270764Y-141097D01*
X270546Y-144013D01*
X270764Y-146930D01*
X271637Y-148972D01*
X272729Y-150722D01*
X274039Y-151888D01*
X275786Y-152763D01*
X280152D01*
G01X253150Y31496D02*
X344488D01*
G01X253150Y39370D02*
G03Y31496I0J-3937D01*
G01D02*
X344488D01*
G01X253150Y39370D02*
G03Y31496I0J-3937D01*
G01Y1937008D02*
G03Y1929134I0J-3937D01*
G01Y1937008D02*
G03Y1929134I0J-3937D01*
G01Y1937008D02*
X344496D01*
G01X253150D02*
X344496D01*
G01X340551Y0D02*
G03X344488Y3937I0J3937D01*
G01X340551Y0D02*
G03X344488Y3937I0J3937D01*
G01X344496Y1964567D02*
G03X340559Y1968504I-3937J0D01*
G01X344496Y1964567D02*
G03X340559Y1968504I-3937J0D01*
G01X356299Y0D02*
X417323D01*
G01X352362Y3937D02*
G03X356299Y0I3937J0D01*
G01X352362Y35433D02*
Y3937D01*
G01Y35433D02*
G03X348425Y39370I-3937J0D01*
G01X344488Y7874D02*
Y3937D01*
G01X352362Y7874D02*
G03X344488I-3937J0D01*
G01Y31496D02*
G03X352362I3937J0D01*
G01X356299Y0D02*
X417323D01*
G01X352362Y3937D02*
G03X356299Y0I3937J0D01*
G01X352362Y35433D02*
Y3937D01*
G01Y35433D02*
G03X348425Y39370I-3937J0D01*
G01X344488Y7874D02*
Y3937D01*
G01X352362Y7874D02*
G03X344488I-3937J0D01*
G01Y31496D02*
G03X352362I3937J0D01*
G01X348425Y1929134D02*
G03X352362Y1933071I0J3937D01*
G01Y1964567D02*
Y1933071D01*
G01X348425Y1929134D02*
G03X352362Y1933071I0J3937D01*
G01Y1964567D02*
Y1933071D01*
G01X356299Y1968504D02*
G03X352362Y1964567I0J-3937D01*
G01X417323Y1968504D02*
X356299D01*
G01X344496Y1960889D02*
Y1964567D01*
G01Y1960889D02*
G03X352370I3937J0D01*
G01Y1937008D02*
G03X344496I-3937J0D01*
G01X356299Y1968504D02*
G03X352362Y1964567I0J-3937D01*
G01X417323Y1968504D02*
X356299D01*
G01X344496Y1960889D02*
Y1964567D01*
G01Y1960889D02*
G03X352370I3937J0D01*
G01Y1937008D02*
G03X344496I-3937J0D01*
G01X404346Y-107763D02*
Y-90263D01*
X408712D01*
X410459Y-91138D01*
X411769Y-92305D01*
X412861Y-94054D01*
X413734Y-96097D01*
X413952Y-99013D01*
X413734Y-101930D01*
X412861Y-103972D01*
X411769Y-105722D01*
X410459Y-106888D01*
X408712Y-107763D01*
X404346D01*
G01X423374Y-99888D02*
X430361D01*
X429706Y-97846D01*
X428614Y-96680D01*
X427086Y-96097D01*
X425557Y-96388D01*
X424247Y-97263D01*
X423374Y-99305D01*
X422937Y-101055D01*
Y-102805D01*
X423374Y-104555D01*
X424466Y-106305D01*
X425776Y-107471D01*
X427304Y-107763D01*
X428832Y-107180D01*
X430361Y-105430D01*
G01X440874Y-105722D02*
X441966Y-106888D01*
X443494Y-107763D01*
X444804D01*
X446114Y-107180D01*
X446987Y-106305D01*
X447424Y-105139D01*
X447206Y-103388D01*
X446332Y-102513D01*
X442402Y-100763D01*
X441529Y-98721D01*
X441966Y-97263D01*
X442839Y-96388D01*
X444149Y-96097D01*
X445459Y-96388D01*
X446769Y-97263D01*
G01X461649Y-96097D02*
Y-107763D01*
G01Y-91430D02*
X461212Y-91138D01*
Y-90555D01*
X461649Y-90263D01*
X462086Y-90555D01*
Y-91138D01*
X461649Y-91430D01*
G01X476092Y-112138D02*
X477621Y-113305D01*
X479367Y-113596D01*
X480895Y-113305D01*
X482206Y-111847D01*
X483079Y-109805D01*
Y-96097D01*
G01Y-98430D02*
X482206Y-97263D01*
X480895Y-96388D01*
X479367Y-96097D01*
X477621Y-96680D01*
X476529Y-97846D01*
X475655Y-99888D01*
X475219Y-101930D01*
X475437Y-103680D01*
X476311Y-105722D01*
X477621Y-107180D01*
X479367Y-107763D01*
X480677Y-107471D01*
X482206Y-106305D01*
X483079Y-105139D01*
G01X492937Y-107763D02*
Y-96097D01*
G01Y-99013D02*
X493811Y-97555D01*
X495121Y-96388D01*
X496867Y-96097D01*
X498395Y-96388D01*
X499706Y-97555D01*
X500361Y-99596D01*
Y-107763D01*
G01X510874Y-99888D02*
X517861D01*
X517206Y-97846D01*
X516114Y-96680D01*
X514586Y-96097D01*
X513057Y-96388D01*
X511747Y-97263D01*
X510874Y-99305D01*
X510437Y-101055D01*
Y-102805D01*
X510874Y-104555D01*
X511966Y-106305D01*
X513276Y-107471D01*
X514804Y-107763D01*
X516332Y-107180D01*
X517861Y-105430D01*
G01X528592Y-107763D02*
Y-96097D01*
G01Y-98430D02*
X529684Y-97263D01*
X530776Y-96388D01*
X532304Y-96097D01*
X533395Y-96388D01*
X534706Y-97263D01*
G01X429722Y-152763D02*
Y-135263D01*
X435399Y-149846D01*
X441076Y-135263D01*
Y-152763D01*
G01X452899D02*
X451152Y-152471D01*
X449624Y-151305D01*
X448314Y-149555D01*
X447440Y-147513D01*
X447004Y-145180D01*
Y-142846D01*
X447440Y-140513D01*
X448314Y-138471D01*
X449624Y-136722D01*
X451152Y-135555D01*
X452899Y-135263D01*
X454645Y-135555D01*
X456174Y-136722D01*
X457484Y-138471D01*
X458358Y-140513D01*
X458794Y-142846D01*
Y-145180D01*
X458358Y-147513D01*
X457484Y-149555D01*
X456174Y-151305D01*
X454645Y-152471D01*
X452899Y-152763D01*
G01X465814Y-150430D02*
X467561Y-151888D01*
X469526Y-152763D01*
X471272D01*
X473019Y-151888D01*
X474329Y-150430D01*
X474984Y-148388D01*
X474547Y-146347D01*
X473456Y-144596D01*
X471491Y-143430D01*
X468871Y-142846D01*
X467342Y-141680D01*
X466687Y-139638D01*
X467124Y-137596D01*
X468216Y-136138D01*
X469744Y-135263D01*
X471272D01*
X472801Y-135846D01*
X474111Y-137305D01*
G01X483314Y-150430D02*
X485061Y-151888D01*
X487026Y-152763D01*
X488772D01*
X490519Y-151888D01*
X491829Y-150430D01*
X492484Y-148388D01*
X492047Y-146347D01*
X490956Y-144596D01*
X488991Y-143430D01*
X486371Y-142846D01*
X484842Y-141680D01*
X484187Y-139638D01*
X484624Y-137596D01*
X485716Y-136138D01*
X487244Y-135263D01*
X488772D01*
X490301Y-135846D01*
X491611Y-137305D01*
G01X509766Y-152763D02*
X501032D01*
Y-135263D01*
X509766D01*
G01X506272Y-143721D02*
X501032D01*
G01X429134Y3937D02*
G03X433071Y0I3937J0D01*
G01X429134Y1964567D02*
Y3937D01*
G01X433071Y0D02*
X494095D01*
G01X421260Y3937D02*
Y1964567D01*
G01X417323Y0D02*
G03X421260Y3937I0J3937D01*
G01X429134Y11811D02*
G03X421260I-3937J0D01*
G01Y42520D02*
G03X429134I3937J0D01*
G01Y3937D02*
G03X433071Y0I3937J0D01*
G01X429134Y1964567D02*
Y3937D01*
G01X433071Y0D02*
X494095D01*
G01X421260Y3937D02*
Y1964567D01*
G01X417323Y0D02*
G03X421260Y3937I0J3937D01*
G01X429134Y11811D02*
G03X421260I-3937J0D01*
G01Y42520D02*
G03X429134I3937J0D01*
G01Y278740D02*
G03X421260I-3937J0D01*
G01X429134D02*
G03X421260I-3937J0D01*
G01Y309449D02*
G03X429134I3937J0D01*
G01X421260D02*
G03X429134I3937J0D01*
G01Y545669D02*
G03X421260I-3937J0D01*
G01X429134D02*
G03X421260I-3937J0D01*
G01Y576378D02*
G03X429134I3937J0D01*
G01X421260D02*
G03X429134I3937J0D01*
G01X421260Y862205D02*
G03X429134I3937J0D01*
G01Y831496D02*
G03X421260I-3937J0D01*
G01Y862205D02*
G03X429134I3937J0D01*
G01Y831496D02*
G03X421260I-3937J0D01*
G01X429134Y1106299D02*
G03X421260I-3937J0D01*
G01X429134D02*
G03X421260I-3937J0D01*
G01Y1137008D02*
G03X429134I3937J0D01*
G01X421260D02*
G03X429134I3937J0D01*
G01X421260Y1422835D02*
G03X429134I3937J0D01*
G01Y1392126D02*
G03X421260I-3937J0D01*
G01Y1422835D02*
G03X429134I3937J0D01*
G01Y1392126D02*
G03X421260I-3937J0D01*
G01X429134Y1659055D02*
G03X421260I-3937J0D01*
G01X429134D02*
G03X421260I-3937J0D01*
G01Y1689764D02*
G03X429134I3937J0D01*
G01X421260D02*
G03X429134I3937J0D01*
G01Y1925984D02*
G03X421260I-3937J0D01*
G01X429134D02*
G03X421260I-3937J0D01*
G01X433071Y1968504D02*
G03X429134Y1964567I0J-3937D01*
G01X494095Y1968504D02*
X433071D01*
G01X421260Y1964567D02*
G03X417323Y1968504I-3937J0D01*
G01X421260Y1956693D02*
G03X429134I3937J0D01*
G01X433071Y1968504D02*
G03X429134Y1964567I0J-3937D01*
G01X494095Y1968504D02*
X433071D01*
G01X421260Y1964567D02*
G03X417323Y1968504I-3937J0D01*
G01X421260Y1956693D02*
G03X429134I3937J0D01*
G01X433071Y1968504D02*
G03X429134Y1964567I0J-3937D01*
G01X421260D02*
G03X417323Y1968504I-3937J0D01*
G01X494095Y0D02*
G03X498032Y3937I0J3937D01*
G01X494095Y0D02*
G03X498032Y3937I0J3937D01*
G01Y1964567D02*
G03X494095Y1968504I-3937J0D01*
G01X498032Y1964567D02*
G03X494095Y1968504I-3937J0D01*
G01X501969Y39370D02*
X631890D01*
G01X501969D02*
G03X498032Y35433I0J-3937D01*
G01Y3937D02*
Y35433D01*
G01X505897Y0D02*
X648386D01*
G01X505897Y7615D02*
Y0D01*
G01X597244Y31496D02*
X505897D01*
G01Y7615D02*
G03X498023I-3937J0D01*
G01Y31496D02*
G03X505897I3937J0D01*
G01X501969Y39370D02*
X631890D01*
G01X501969D02*
G03X498032Y35433I0J-3937D01*
G01Y3937D02*
Y35433D01*
G01X505897Y0D02*
X620827D01*
G01X505897Y7615D02*
Y0D01*
G01X597244Y31496D02*
X505897D01*
G01Y7615D02*
G03X498023I-3937J0D01*
G01Y31496D02*
G03X505897I3937J0D01*
G01X498032Y1933071D02*
Y1960630D01*
G01Y1933071D02*
G03X501969Y1929134I3937J0D01*
G01X631890D02*
X501969D01*
G01X498032Y1933071D02*
Y1964567D01*
G01Y1933071D02*
G03X501969Y1929134I3937J0D01*
G01X631890D02*
X501969D01*
G01X505906Y1960630D02*
Y1968504D01*
G01D02*
X648386D01*
G01X597244Y1937008D02*
X505906D01*
G01X498032Y1960630D02*
G03X505906I3937J0D01*
G01Y1937008D02*
G03X498032I-3937J0D01*
G01X505906Y1960630D02*
Y1968504D01*
G01D02*
X620827D01*
G01X597244Y1937008D02*
X505906D01*
G01X498032Y1960630D02*
G03X505906I3937J0D01*
G01Y1937008D02*
G03X498032I-3937J0D01*
G01X575349Y-152763D02*
Y-135263D01*
X572729Y-138763D01*
G01Y-152763D02*
X577969D01*
G01X588701Y-138180D02*
X590011Y-136430D01*
X591539Y-135555D01*
X593286Y-135263D01*
X595469Y-135846D01*
X596997Y-137305D01*
X597434Y-139054D01*
X597216Y-140805D01*
X596342Y-142263D01*
X591976Y-145180D01*
X590011Y-147221D01*
X588701Y-150139D01*
X588264Y-152763D01*
X597434D01*
G01X606419Y-153346D02*
X614279Y-135263D01*
G01X627849Y-152763D02*
Y-135263D01*
X625229Y-138763D01*
G01Y-152763D02*
X630469D01*
G01X645349D02*
Y-135263D01*
X642729Y-138763D01*
G01Y-152763D02*
X647969D01*
G01X658919Y-153346D02*
X666779Y-135263D01*
G01X676201Y-138180D02*
X677511Y-136430D01*
X679039Y-135555D01*
X680786Y-135263D01*
X682969Y-135846D01*
X684497Y-137305D01*
X684934Y-139054D01*
X684716Y-140805D01*
X683842Y-142263D01*
X679476Y-145180D01*
X677511Y-147221D01*
X676201Y-150139D01*
X675764Y-152763D01*
X684934D01*
G01X697849Y-135263D02*
X696102Y-135846D01*
X694792Y-137305D01*
X693919Y-139054D01*
X693264Y-141388D01*
X693046Y-144013D01*
X693264Y-146638D01*
X693919Y-148972D01*
X694792Y-150722D01*
X696102Y-152180D01*
X697849Y-152763D01*
X699595Y-152180D01*
X700906Y-150722D01*
X701779Y-148972D01*
X702434Y-146638D01*
X702652Y-144013D01*
X702434Y-141388D01*
X701779Y-139054D01*
X700906Y-137305D01*
X699595Y-135846D01*
X697849Y-135263D01*
G01X715349Y-152763D02*
Y-135263D01*
X712729Y-138763D01*
G01Y-152763D02*
X717969D01*
G01X728046Y-150139D02*
X729355Y-151597D01*
X730884Y-152471D01*
X732849Y-152763D01*
X734814Y-152180D01*
X736342Y-151013D01*
X737434Y-148972D01*
X737652Y-146638D01*
X737216Y-144305D01*
X736124Y-142846D01*
X734595Y-141680D01*
X733067Y-141388D01*
X731539Y-141680D01*
X729574Y-142846D01*
X730229Y-135263D01*
X736124D01*
G01X623046Y-107763D02*
Y-90263D01*
X627412D01*
X629159Y-91138D01*
X630469Y-92305D01*
X631561Y-94054D01*
X632434Y-96097D01*
X632652Y-99013D01*
X632434Y-101930D01*
X631561Y-103972D01*
X630469Y-105722D01*
X629159Y-106888D01*
X627412Y-107763D01*
X623046D01*
G01X649279D02*
Y-96097D01*
G01Y-98138D02*
X648406Y-96972D01*
X647095Y-96388D01*
X645567Y-96097D01*
X644039Y-96680D01*
X642729Y-97846D01*
X641855Y-99596D01*
X641419Y-101930D01*
X641855Y-104263D01*
X642729Y-106013D01*
X644039Y-107180D01*
X645567Y-107763D01*
X647095Y-107471D01*
X648406Y-106597D01*
X649279Y-105430D01*
G01X662849Y-90263D02*
Y-107763D01*
G01X659792Y-96097D02*
X665906D01*
G01X677074Y-99888D02*
X684061D01*
X683406Y-97846D01*
X682314Y-96680D01*
X680786Y-96097D01*
X679257Y-96388D01*
X677947Y-97263D01*
X677074Y-99305D01*
X676637Y-101055D01*
Y-102805D01*
X677074Y-104555D01*
X678166Y-106305D01*
X679476Y-107471D01*
X681004Y-107763D01*
X682532Y-107180D01*
X684061Y-105430D01*
G01X643701Y169256D02*
Y39370D01*
G01X635827Y31496D02*
G03X643701Y39370I0J7874D01*
G01X650689Y19685D02*
G03I-6988J0D01*
G01X631890Y39370D02*
G03X635827Y43307I0J3937D01*
G01Y31496D02*
X627953D01*
G01X597244D02*
G03Y39370I0J3937D01*
G01X627953D02*
G03Y31496I0J-3937D01*
G01X650689Y19685D02*
G03I-6988J0D01*
G01X631890Y39370D02*
G03X635827Y43307I0J3937D01*
G01Y31496D02*
X627953D01*
G01X597244D02*
G03Y39370I0J3937D01*
G01X627953D02*
G03Y31496I0J-3937D01*
G01X635827Y161417D02*
Y43307D01*
G01X643701Y169256D02*
G03X635827I-3937J0D01*
G01X643701D02*
G03X635827I-3937J0D01*
G01Y161417D02*
Y1807087D01*
G01Y161417D02*
Y1807087D01*
G01X643701Y436186D02*
Y199965D01*
G01X635827D02*
G03X643701I3937J0D01*
G01X635827D02*
G03X643701I3937J0D01*
G01Y436186D02*
G03X635827I-3937J0D01*
G01X643701D02*
G03X635827I-3937J0D01*
G01X643701Y703115D02*
Y466894D01*
G01X635827D02*
G03X643701I3937J0D01*
G01X635827D02*
G03X643701I3937J0D01*
G01Y703115D02*
G03X635827I-3937J0D01*
G01X643701D02*
G03X635827I-3937J0D01*
G01X643701Y970832D02*
Y733823D01*
G01X635827D02*
G03X643701I3937J0D01*
G01X635827D02*
G03X643701I3937J0D01*
G01Y1234611D02*
Y997603D01*
G01X635827D02*
G03X643701I3937J0D01*
G01Y970832D02*
G03X635827I-3937J0D01*
G01Y997603D02*
G03X643701I3937J0D01*
G01Y970832D02*
G03X635827I-3937J0D01*
G01X643701Y1501541D02*
Y1265320D01*
G01X635827D02*
G03X643701I3937J0D01*
G01Y1234611D02*
G03X635827I-3937J0D01*
G01Y1265320D02*
G03X643701I3937J0D01*
G01Y1234611D02*
G03X635827I-3937J0D01*
G01X643701Y1501541D02*
G03X635827I-3937J0D01*
G01X643701D02*
G03X635827I-3937J0D01*
G01X643701Y1768470D02*
Y1532249D01*
G01X635827D02*
G03X643701I3937J0D01*
G01X635827D02*
G03X643701I3937J0D01*
G01Y1768470D02*
G03X635827I-3937J0D01*
G01X643701D02*
G03X635827I-3937J0D01*
G01Y1799178D02*
G03X643701I3937J0D01*
G01X635827D02*
G03X643701I3937J0D01*
G01Y1929134D02*
Y1799178D01*
G01X635827Y1818898D02*
Y1807087D01*
G01Y1818898D02*
Y1925197D01*
G01Y1818898D02*
Y1925197D01*
G01X643701Y1929134D02*
G03X635827Y1937008I-7874J0D01*
G01Y1925197D02*
G03X631890Y1929134I-3937J0D01*
G01X627953Y1937008D02*
G03Y1929134I0J-3937D01*
G01X597244D02*
G03Y1937008I0J3937D01*
G01X635827Y1925197D02*
G03X631890Y1929134I-3937J0D01*
G01X627953Y1937008D02*
G03Y1929134I0J-3937D01*
G01X597244D02*
G03Y1937008I0J3937D01*
G01X650689Y1948819D02*
G03I-6988J0D01*
G01X627953Y1937008D02*
X635827D01*
G01X650689Y1948819D02*
G03I-6988J0D01*
G01X627953Y1937008D02*
X635827D01*
G01X650689Y1948819D02*
G03I-6988J0D01*
G01X648386Y0D02*
G03X663386Y15000I0J15000D01*
G01Y1953504D02*
Y15000D01*
G01Y1953504D02*
G03X648386Y1968504I-15000J0D01*
M02*
